# S9S_MB_2U (Grand Teton) — schematic netlist excerpt (pin names and nets, part order shuffled) for the footprints in the layout excerpt that follows; sources: Cadence DE-HDL packaged netlist, KiCad conversion of 03242023_DA0F0TMBIJ0_F0T_Motherboard_J_brd_V01_OCP.brd

R2579  Q_RES  0 5% CHIP  pkg 0402LF  page 296 : A = SVID_DIO1_CPU1_R ; B = SVID_DIO_PVCCD_HV_CPU1_R
C1276  Q_CAP  22UF 16V 20% X6S  pkg C0805  page 191 : A = P12V_E1S_0 ; B = GND

Q101  MOSFET_NCH_DUAL  PJT138K IC  pkg SOT363XD  page 147
  S1  = GND
  G1  = GPU_FPGA_THERM_OVERT_N
  D2  = GPU_FPGA_THERM_OVERT_ISO_N
  S2  = GND
  G2  = GPU_FPGA_THERM_OVERT
  D1  = GPU_FPGA_THERM_OVERT

(kicad_pcb
	(version 20260206)
	(generator "pcbnew")
	(generator_version "10.0")
	(general
		(thickness 1.6)
		(legacy_teardrops no)
	)
	(paper "A4")
	(title_block
		(title "03242023_DA0F0TMBIJ0_F0T_Motherboard_J_brd_V01_OCP.brd")
		(comment 1 "Grand Teton / footprints 511-513 of 6105")
	)
	(layers
		(0 "F.Cu" signal "TOP")
		(4 "In1.Cu" signal "GND")
		(6 "In2.Cu" signal "IN1")
		(8 "In3.Cu" signal "GND1")
		(10 "In4.Cu" signal "IN2")
		(12 "In5.Cu" signal "GND2")
		(14 "In6.Cu" signal "IN3")
		(16 "In7.Cu" signal "GND3")
		(18 "In8.Cu" signal "VCC")
		(20 "In9.Cu" signal "VCC1")
		(22 "In10.Cu" signal "GND4")
		(24 "In11.Cu" signal "IN4")
		(26 "In12.Cu" signal "GND5")
		(28 "In13.Cu" signal "IN5")
		(30 "In14.Cu" signal "GND6")
		(32 "In15.Cu" signal "IN6")
		(34 "In16.Cu" signal "GND7")
		(2 "B.Cu" signal "BOTTOM")
		(9 "F.Adhes" user "F.Adhesive")
		(11 "B.Adhes" user "B.Adhesive")
		(13 "F.Paste" user "Package Geometry/Pastemask Top")
		(15 "B.Paste" user "Package Geometry/Pastemask Bottom")
		(5 "F.SilkS" user "Ref Des/Silkscreen Top")
		(7 "B.SilkS" user "Ref Des/Silkscreen Bottom")
		(1 "F.Mask" user "Board Geometry/Soldermask Top")
		(3 "B.Mask" user "Board Geometry/Soldermask Bottom")
		(17 "Dwgs.User" user "User.Drawings")
		(19 "Cmts.User" user "User.Comments")
		(21 "Eco1.User" user "User.Eco1")
		(23 "Eco2.User" user "User.Eco2")
		(25 "Edge.Cuts" user "Board Geometry/Outline")
		(27 "Margin" user)
		(31 "F.CrtYd" user "Package Geometry/Place Bound Top")
		(29 "B.CrtYd" user "Package Geometry/Place Bound Bottom")
		(35 "F.Fab" user "Ref Des/Assembly Top")
		(33 "B.Fab" user "Ref Des/Assembly Bottom")
	)
	(footprint ""
		(layer "F.Cu")
		(at 22.13356 -164.735256)
		(property "Reference" "R2579"
			(at 0 0 0)
			(layer "F.SilkS")
			(hide yes)
			(effects
				(font
					(size 1.27 1.27)
				)
			)
		)
		(property "Value" ""
			(at 0 0 0)
			(layer "F.Fab")
			(effects
				(font
					(size 1.27 1.27)
				)
			)
		)
		(duplicate_pad_numbers_are_jumpers no)
		(fp_line
			(start -0.7874 -0.4064)
			(end 0.7874 -0.4064)
			(stroke
				(width 0.1524)
				(type default)
			)
			(layer "F.SilkS")
		)
		(fp_line
			(start -0.7874 0.4064)
			(end -0.7874 -0.4064)
			(stroke
				(width 0.1524)
				(type default)
			)
			(layer "F.SilkS")
		)
		(fp_line
			(start 0.7874 -0.4064)
			(end 0.7874 0.4064)
			(stroke
				(width 0.1524)
				(type default)
			)
			(layer "F.SilkS")
		)
		(fp_line
			(start 0.7874 0.4064)
			(end -0.7874 0.4064)
			(stroke
				(width 0.1524)
				(type default)
			)
			(layer "F.SilkS")
		)
		(fp_line
			(start -0.67945 -0.305054)
			(end -0.12065 -0.305054)
			(stroke
				(width 0.1)
				(type default)
			)
			(layer "F.Fab")
		)
		(fp_line
			(start -0.67945 0.3048)
			(end -0.67945 -0.305054)
			(stroke
				(width 0.1)
				(type default)
			)
			(layer "F.Fab")
		)
		(fp_line
			(start -0.12065 -0.305054)
			(end -0.12065 -0.2794)
			(stroke
				(width 0.1)
				(type default)
			)
			(layer "F.Fab")
		)
		(fp_line
			(start -0.12065 -0.2794)
			(end 0.12065 -0.2794)
			(stroke
				(width 0.1)
				(type default)
			)
			(layer "F.Fab")
		)
		(fp_line
			(start -0.12065 0.2794)
			(end -0.12065 0.3048)
			(stroke
				(width 0.1)
				(type default)
			)
			(layer "F.Fab")
		)
		(fp_line
			(start -0.12065 0.3048)
			(end -0.67945 0.3048)
			(stroke
				(width 0.1)
				(type default)
			)
			(layer "F.Fab")
		)
		(fp_line
			(start 0.120396 0.2794)
			(end -0.12065 0.2794)
			(stroke
				(width 0.1)
				(type default)
			)
			(layer "F.Fab")
		)
		(fp_line
			(start 0.120396 0.3048)
			(end 0.120396 0.2794)
			(stroke
				(width 0.1)
				(type default)
			)
			(layer "F.Fab")
		)
		(fp_line
			(start 0.12065 -0.3048)
			(end 0.67945 -0.3048)
			(stroke
				(width 0.1)
				(type default)
			)
			(layer "F.Fab")
		)
		(fp_line
			(start 0.12065 -0.2794)
			(end 0.12065 -0.3048)
			(stroke
				(width 0.1)
				(type default)
			)
			(layer "F.Fab")
		)
		(fp_line
			(start 0.67945 -0.3048)
			(end 0.67945 0.3048)
			(stroke
				(width 0.1)
				(type default)
			)
			(layer "F.Fab")
		)
		(fp_line
			(start 0.67945 0.3048)
			(end 0.120396 0.3048)
			(stroke
				(width 0.1)
				(type default)
			)
			(layer "F.Fab")
		)
		(pad "1" smd circle
			(at -0.40005 0)
			(size 0 0)
			(layers "F.Cu" "F.Mask" "F.Paste")
			(net "SVID_DIO1_CPU1_R")
		)
		(pad "2" smd circle
			(at 0.40005 0)
			(size 0 0)
			(layers "F.Cu" "F.Mask" "F.Paste")
			(net "SVID_DIO_PVCCD_HV_CPU1_R")
		)
	)
	(footprint ""
		(layer "F.Cu")
		(at 243.446808 -40.920162 -90)
		(property "Reference" "C1276"
			(at 0 0 270)
			(layer "F.SilkS")
			(hide yes)
			(effects
				(font
					(size 1.27 1.27)
				)
			)
		)
		(property "Value" ""
			(at 0 0 270)
			(layer "F.Fab")
			(effects
				(font
					(size 1.27 1.27)
				)
			)
		)
		(duplicate_pad_numbers_are_jumpers no)
		(fp_line
			(start -1.524 0.762)
			(end -1.524 -0.762)
			(stroke
				(width 0.1524)
				(type default)
			)
			(layer "F.SilkS")
		)
		(fp_line
			(start 1.524 0.762)
			(end -1.524 0.762)
			(stroke
				(width 0.1524)
				(type default)
			)
			(layer "F.SilkS")
		)
		(fp_line
			(start -1.524 -0.762)
			(end 1.524 -0.762)
			(stroke
				(width 0.1524)
				(type default)
			)
			(layer "F.SilkS")
		)
		(fp_line
			(start 1.524 -0.762)
			(end 1.524 0.762)
			(stroke
				(width 0.1524)
				(type default)
			)
			(layer "F.SilkS")
		)
		(fp_line
			(start -1.1049 0.724916)
			(end 1.1049 0.724916)
			(stroke
				(width 0.1)
				(type default)
			)
			(layer "F.Fab")
		)
		(fp_line
			(start 1.1049 0.724916)
			(end 1.1049 -0.724916)
			(stroke
				(width 0.1)
				(type default)
			)
			(layer "F.Fab")
		)
		(fp_line
			(start -1.1049 -0.724916)
			(end -1.1049 0.724916)
			(stroke
				(width 0.1)
				(type default)
			)
			(layer "F.Fab")
		)
		(fp_line
			(start 1.1049 -0.724916)
			(end -1.1049 -0.724916)
			(stroke
				(width 0.1)
				(type default)
			)
			(layer "F.Fab")
		)
		(pad "1" smd rect
			(at -0.889 0 90)
			(size 1.016 1.27)
			(layers "F.Cu" "F.Mask" "F.Paste")
			(net "P12V_E1S_0")
		)
		(pad "2" smd rect
			(at 0.889 0 90)
			(size 1.016 1.27)
			(layers "F.Cu" "F.Mask" "F.Paste")
			(net "GND")
		)
	)
	(footprint ""
		(layer "F.Cu")
		(at 28.081732 -406.687274)
		(property "Reference" "Q101"
			(at 0.40894 -2.037588 0)
			(unlocked yes)
			(layer "F.SilkS")
			(effects
				(font
					(size 0.7874 0.5842)
					(thickness 0.1524)
				)
				(justify left)
			)
		)
		(property "Value" ""
			(at 0 0 0)
			(layer "F.Fab")
			(effects
				(font
					(size 1.27 1.27)
				)
			)
		)
		(duplicate_pad_numbers_are_jumpers no)
		(fp_line
			(start -1.332738 -1.100074)
			(end -0.4826 -1.100074)
			(stroke
				(width 0.1524)
				(type default)
			)
			(layer "F.SilkS")
		)
		(fp_line
			(start -1.332738 1.100074)
			(end -1.332738 -1.100074)
			(stroke
				(width 0.1524)
				(type default)
			)
			(layer "F.SilkS")
		)
		(fp_line
			(start -0.4826 -1.100074)
			(end 0 -0.541274)
			(stroke
				(width 0.1524)
				(type default)
			)
			(layer "F.SilkS")
		)
		(fp_line
			(start 0 -0.541274)
			(end 0.4826 -1.100074)
			(stroke
				(width 0.1524)
				(type default)
			)
			(layer "F.SilkS")
		)
		(fp_line
			(start 0.4826 -1.100074)
			(end 1.332738 -1.100074)
			(stroke
				(width 0.1524)
				(type default)
			)
			(layer "F.SilkS")
		)
		(fp_line
			(start 1.332738 -1.100074)
			(end 1.332738 1.100074)
			(stroke
				(width 0.1524)
				(type default)
			)
			(layer "F.SilkS")
		)
		(fp_line
			(start 1.332738 1.100074)
			(end -1.332738 1.100074)
			(stroke
				(width 0.1524)
				(type default)
			)
			(layer "F.SilkS")
		)
		(fp_poly
			(pts
				(xy -1.895602 -1.706626) (xy -1.647444 -0.961898) (xy -2.392172 -1.210056)
			)
			(stroke
				(width 0)
				(type default)
			)
			(fill yes)
			(layer "F.SilkS")
		)
		(fp_line
			(start -0.674878 -1.100074)
			(end 0.674878 -1.100074)
			(stroke
				(width 0.1)
				(type default)
			)
			(layer "F.Fab")
		)
		(fp_line
			(start -0.674878 1.100074)
			(end -0.674878 -1.100074)
			(stroke
				(width 0.1)
				(type default)
			)
			(layer "F.Fab")
		)
		(fp_line
			(start 0.674878 -1.100074)
			(end 0.674878 1.100074)
			(stroke
				(width 0.1)
				(type default)
			)
			(layer "F.Fab")
		)
		(fp_line
			(start 0.674878 1.100074)
			(end -0.674878 1.100074)
			(stroke
				(width 0.1)
				(type default)
			)
			(layer "F.Fab")
		)
		(fp_poly
			(pts
				(xy -2.2352 -0.298958) (xy -2.2352 -1.001014) (xy -1.533144 -0.649986)
			)
			(stroke
				(width 0)
				(type default)
			)
			(fill yes)
			(layer "F.Fab")
		)
		(pad "1" smd rect
			(at -0.94996 -0.649986 90)
			(size 0.4318 0.508)
			(layers "F.Cu" "F.Mask" "F.Paste")
			(net "GND")
		)
		(pad "2" smd rect
			(at -0.94996 0 90)
			(size 0.4318 0.508)
			(layers "F.Cu" "F.Mask" "F.Paste")
			(net "GPU_FPGA_THERM_OVERT_N")
		)
		(pad "3" smd rect
			(at -0.94996 0.649986 90)
			(size 0.4318 0.508)
			(layers "F.Cu" "F.Mask" "F.Paste")
			(net "GPU_FPGA_THERM_OVERT_ISO_N")
		)
		(pad "4" smd rect
			(at 0.94996 0.649986 90)
			(size 0.4318 0.508)
			(layers "F.Cu" "F.Mask" "F.Paste")
			(net "GND")
		)
		(pad "5" smd rect
			(at 0.94996 0 90)
			(size 0.4318 0.508)
			(layers "F.Cu" "F.Mask" "F.Paste")
			(net "GPU_FPGA_THERM_OVERT")
		)
		(pad "6" smd rect
			(at 0.94996 -0.649986 90)
			(size 0.4318 0.508)
			(layers "F.Cu" "F.Mask" "F.Paste")
			(net "GPU_FPGA_THERM_OVERT")
		)
	)
)
